(kicad_pcb
	(version 20240108)
	(generator "pcbnew")
	(generator_version "8.0")
	(general
		(thickness 1.62)
		(legacy_teardrops no)
	)
	(paper "A4")
	(title_block
		(title "Jetson Orin Baseboard")
		(date "2025-03-12")
		(rev "1.3.4")
		(company "Antmicro Ltd")
		(comment 1 "www.antmicro.com")
		(comment 9 "footprints 53-57 of 677")
	)
	(layers
		(0 "F.Cu" signal)
		(1 "In1.Cu" signal)
		(2 "In2.Cu" signal)
		(3 "In3.Cu" signal)
		(4 "In4.Cu" jumper)
		(5 "In5.Cu" signal)
		(6 "In6.Cu" signal)
		(31 "B.Cu" signal)
		(32 "B.Adhes" user "B.Adhesive")
		(33 "F.Adhes" user "F.Adhesive")
		(34 "B.Paste" user)
		(35 "F.Paste" user)
		(36 "B.SilkS" user "B.Silkscreen")
		(37 "F.SilkS" user "F.Silkscreen")
		(38 "B.Mask" user)
		(39 "F.Mask" user)
		(40 "Dwgs.User" user "User.Drawings")
		(41 "Cmts.User" user "User.Comments")
		(42 "Eco1.User" user "User.Eco1")
		(43 "Eco2.User" user "User.Eco2")
		(44 "Edge.Cuts" user)
		(45 "Margin" user)
		(46 "B.CrtYd" user "B.Courtyard")
		(47 "F.CrtYd" user "F.Courtyard")
		(48 "B.Fab" user)
		(49 "F.Fab" user)
	)
	(footprint "antmicro-footprints:FB_0805_2012Metric"
		(layer "F.Cu")
		(at 86.25 117.95)
		(descr "FERRITE BEAD 0805")
		(tags "FERRITE BEAD 0805")
		(property "Reference" "FB4"
			(at -1.575 -0.8 0)
			(layer "F.SilkS")
			(effects
				(font
					(size 0.6 0.6)
					(thickness 0.15)
				)
				(justify left bottom)
			)
		)
		(property "Value" "FB_220Z_2A_Murata-BLM21PG_0805"
			(at 0 1.8 0)
			(layer "F.Fab")
			(effects
				(font
					(size 0.7 0.7)
					(thickness 0.15)
				)
				(justify left bottom)
			)
		)
		(property "Footprint" "antmicro-footprints:FB_0805_2012Metric"
			(at 0 0 0)
			(layer "F.Fab")
			(hide yes)
			(effects
				(font
					(size 1.27 1.27)
					(thickness 0.15)
				)
			)
		)
		(property "Datasheet" "https://www.murata.com/products/productdata/8796738977822/ENFA0005.pdf?1653276712000"
			(at 0 0 0)
			(layer "F.Fab")
			(hide yes)
			(effects
				(font
					(size 1.27 1.27)
					(thickness 0.15)
				)
			)
		)
		(property "Author" "Antmicro"
			(at 0 0 0)
			(layer "F.Fab")
			(hide yes)
			(effects
				(font
					(size 1 1)
					(thickness 0.15)
				)
			)
		)
		(property "Current" ""
			(at 0 0 0)
			(layer "F.Fab")
			(hide yes)
			(effects
				(font
					(size 1 1)
					(thickness 0.15)
				)
			)
		)
		(property "License" "Apache-2.0"
			(at 0 0 0)
			(layer "F.Fab")
			(hide yes)
			(effects
				(font
					(size 1 1)
					(thickness 0.15)
				)
			)
		)
		(property "MPN" "BLM21PG221SN1D"
			(at 0 0 0)
			(layer "F.Fab")
			(hide yes)
			(effects
				(font
					(size 1 1)
					(thickness 0.15)
				)
			)
		)
		(property "Manufacturer" "Murata"
			(at 0 0 0)
			(layer "F.Fab")
			(hide yes)
			(effects
				(font
					(size 1 1)
					(thickness 0.15)
				)
			)
		)
		(property "Val" "220Z/2A"
			(at 0 0 0)
			(layer "F.Fab")
			(hide yes)
			(effects
				(font
					(size 1 1)
					(thickness 0.15)
				)
			)
		)
		(sheetname "HDMI")
		(sheetfile "hdmi.kicad_sch")
		(attr smd)
		(fp_line
			(start -0.319 0.698)
			(end 0.281 0.698)
			(stroke
				(width 0.15)
				(type solid)
			)
			(layer "F.SilkS")
		)
		(fp_line
			(start -0.299 -0.698)
			(end 0.299 -0.698)
			(stroke
				(width 0.15)
				(type solid)
			)
			(layer "F.SilkS")
		)
		(fp_rect
			(start 1.95 -0.9)
			(end -1.95 0.9)
			(stroke
				(width 0.05)
				(type default)
			)
			(fill none)
			(layer "F.CrtYd")
		)
		(fp_line
			(start -0.948 -0.681)
			(end 0.948 -0.681)
			(stroke
				(width 0.15)
				(type solid)
			)
			(layer "F.Fab")
		)
		(fp_line
			(start -0.948 -0.676)
			(end -0.948 0.676)
			(stroke
				(width 0.15)
				(type solid)
			)
			(layer "F.Fab")
		)
		(fp_line
			(start -0.948 0.681)
			(end 0.948 0.681)
			(stroke
				(width 0.15)
				(type solid)
			)
			(layer "F.Fab")
		)
		(fp_line
			(start 0.948 -0.676)
			(end 0.948 0.676)
			(stroke
				(width 0.15)
				(type solid)
			)
			(layer "F.Fab")
		)
		(fp_text user "License: Apache-2.0"
			(at -1.9 5.75 0)
			(layer "F.Fab")
			(hide yes)
			(effects
				(font
					(size 0.7 0.7)
					(thickness 0.15)
				)
				(justify left bottom)
			)
		)
		(fp_text user "Author: Antmicro"
			(at -1.9 4.4 0)
			(layer "F.Fab")
			(hide yes)
			(effects
				(font
					(size 0.7 0.7)
					(thickness 0.15)
				)
				(justify left bottom)
			)
		)
		(fp_text user "${REFERENCE}"
			(at -1.9 3.1 0)
			(layer "F.Fab")
			(hide yes)
			(effects
				(font
					(size 0.7 0.7)
					(thickness 0.15)
				)
				(justify left bottom)
			)
		)
		(pad "1" smd roundrect
			(at -1.1 0)
			(size 1.2 1.3)
			(layers "F.Cu" "F.Paste" "F.Mask")
			(roundrect_rratio 0.25)
			(net 99 "+5V")
			(pintype "passive")
		)
		(pad "2" smd roundrect
			(at 1.1 0)
			(size 1.2 1.3)
			(layers "F.Cu" "F.Paste" "F.Mask")
			(roundrect_rratio 0.25)
			(net 424 "Net-(D38-A)")
			(pintype "passive")
		)
	)
	(footprint "antmicro-footprints:SW_KMR211NGLFS_SMD"
		(layer "F.Cu")
		(at 122.9 125.9 180)
		(property "Reference" "S2"
			(at 2.25 2.03 180)
			(layer "F.SilkS")
			(effects
				(font
					(size 0.7 0.7)
					(thickness 0.15)
				)
				(justify left bottom)
			)
		)
		(property "Value" "SW_KMR211NGLFS_SMD"
			(at -3 3 180)
			(layer "F.Fab")
			(effects
				(font
					(size 0.7 0.7)
					(thickness 0.15)
				)
				(justify left bottom)
			)
		)
		(property "Footprint" "antmicro-footprints:SW_KMR211NGLFS_SMD"
			(at 0 0 180)
			(layer "F.Fab")
			(hide yes)
			(effects
				(font
					(size 1.27 1.27)
					(thickness 0.15)
				)
			)
		)
		(property "Datasheet" "http://www.farnell.com/datasheets/2631211.pdf"
			(at 0 0 180)
			(layer "F.Fab")
			(hide yes)
			(effects
				(font
					(size 1.27 1.27)
					(thickness 0.15)
				)
			)
		)
		(property "Author" "Antmicro"
			(at 245.8 251.8 0)
			(layer "F.Fab")
			(hide yes)
			(effects
				(font
					(size 1 1)
					(thickness 0.15)
				)
			)
		)
		(property "License" "Apache-2.0"
			(at 245.8 251.8 0)
			(layer "F.Fab")
			(hide yes)
			(effects
				(font
					(size 1 1)
					(thickness 0.15)
				)
			)
		)
		(property "MPN" "KMR211NGLFS"
			(at 245.8 251.8 0)
			(layer "F.Fab")
			(hide yes)
			(effects
				(font
					(size 1 1)
					(thickness 0.15)
				)
			)
		)
		(property "Manufacturer" "C&K"
			(at 245.8 251.8 0)
			(layer "F.Fab")
			(hide yes)
			(effects
				(font
					(size 1 1)
					(thickness 0.15)
				)
			)
		)
		(sheetname "Peripherals")
		(sheetfile "peripherals.kicad_sch")
		(attr smd)
		(fp_line
			(start 2.101 1.601)
			(end 2.101 1.48)
			(stroke
				(width 0.15)
				(type solid)
			)
			(layer "F.SilkS")
		)
		(fp_line
			(start 2.101 1.601)
			(end -2.1 1.601)
			(stroke
				(width 0.15)
				(type solid)
			)
			(layer "F.SilkS")
		)
		(fp_line
			(start 2.101 -1.58)
			(end 2.101 -1.459)
			(stroke
				(width 0.15)
				(type solid)
			)
			(layer "F.SilkS")
		)
		(fp_line
			(start 2.101 -1.6)
			(end -2.1 -1.6)
			(stroke
				(width 0.15)
				(type solid)
			)
			(layer "F.SilkS")
		)
		(fp_line
			(start -2.1 1.601)
			(end -2.1 1.48)
			(stroke
				(width 0.15)
				(type solid)
			)
			(layer "F.SilkS")
		)
		(fp_line
			(start -2.1 -1.6)
			(end -2.1 -1.499)
			(stroke
				(width 0.15)
				(type solid)
			)
			(layer "F.SilkS")
		)
		(fp_rect
			(start 2.751 1.75)
			(end -2.748 -1.749)
			(stroke
				(width 0.05)
				(type solid)
			)
			(fill none)
			(layer "F.CrtYd")
		)
		(fp_line
			(start 2.101 1.601)
			(end 2.101 -1.6)
			(stroke
				(width 0.15)
				(type solid)
			)
			(layer "F.Fab")
		)
		(fp_line
			(start 2.101 -1.6)
			(end -2.1 -1.6)
			(stroke
				(width 0.15)
				(type solid)
			)
			(layer "F.Fab")
		)
		(fp_line
			(start 0.25 0.802)
			(end -0.248 0.802)
			(stroke
				(width 0.15)
				(type solid)
			)
			(layer "F.Fab")
		)
		(fp_line
			(start -0.248 -0.8)
			(end 0.25 -0.8)
			(stroke
				(width 0.15)
				(type solid)
			)
			(layer "F.Fab")
		)
		(fp_line
			(start -2.1 1.601)
			(end 2.101 1.601)
			(stroke
				(width 0.15)
				(type solid)
			)
			(layer "F.Fab")
		)
		(fp_line
			(start -2.1 -1.6)
			(end -2.1 1.601)
			(stroke
				(width 0.15)
				(type solid)
			)
			(layer "F.Fab")
		)
		(fp_arc
			(start 0.25 -0.8)
			(mid 1.051001 0.001)
			(end 0.25 0.802)
			(stroke
				(width 0.15)
				(type solid)
			)
			(layer "F.Fab")
		)
		(fp_arc
			(start -0.248 0.802)
			(mid -1.050001 0.001)
			(end -0.248 -0.8)
			(stroke
				(width 0.15)
				(type solid)
			)
			(layer "F.Fab")
		)
		(fp_text user "${REFERENCE}"
			(at -3 4.25 180)
			(layer "F.Fab")
			(hide yes)
			(effects
				(font
					(size 0.7 0.7)
					(thickness 0.15)
				)
				(justify left bottom)
			)
		)
		(fp_text user "License: Apache-2.0"
			(at -3 6.75 180)
			(layer "F.Fab")
			(hide yes)
			(effects
				(font
					(size 0.7 0.7)
					(thickness 0.15)
				)
				(justify left bottom)
			)
		)
		(fp_text user "Author: Antmicro"
			(at -3 5.5 180)
			(layer "F.Fab")
			(hide yes)
			(effects
				(font
					(size 0.7 0.7)
					(thickness 0.15)
				)
				(justify left bottom)
			)
		)
		(pad "1" smd rect
			(at -2.048 -0.8)
			(size 0.9 1)
			(layers "F.Cu" "F.Paste" "F.Mask")
			(net 45 "USER_BTN0")
			(pinfunction "1")
			(pintype "passive")
		)
		(pad "2" smd rect
			(at 2.05 -0.8)
			(size 0.9 1)
			(layers "F.Cu" "F.Paste" "F.Mask")
			(net 45 "USER_BTN0")
			(pinfunction "2")
			(pintype "passive")
		)
		(pad "3" smd rect
			(at -2.048 0.802)
			(size 0.9 1)
			(layers "F.Cu" "F.Paste" "F.Mask")
			(net 1 "GND")
			(pinfunction "3")
			(pintype "passive")
		)
		(pad "4" smd rect
			(at 2.05 0.802)
			(size 0.9 1)
			(layers "F.Cu" "F.Paste" "F.Mask")
			(net 1 "GND")
			(pinfunction "4")
			(pintype "passive")
		)
	)
	(footprint "antmicro-footprints:R_0402_1005Metric"
		(layer "F.Cu")
		(at 105.154938 110)
		(descr "Resistor SMD 0402")
		(tags "resistor SMD 0402")
		(property "Reference" "R200"
			(at -3.654938 0.4 0)
			(layer "F.SilkS")
			(effects
				(font
					(size 0.7 0.7)
					(thickness 0.15)
				)
				(justify left bottom)
			)
		)
		(property "Value" "R_0R_0402"
			(at 0 1.4 0)
			(layer "F.Fab")
			(effects
				(font
					(size 0.7 0.7)
					(thickness 0.15)
				)
				(justify left bottom)
			)
		)
		(property "Footprint" "antmicro-footprints:R_0402_1005Metric"
			(at 0 0 0)
			(layer "F.Fab")
			(hide yes)
			(effects
				(font
					(size 1.27 1.27)
					(thickness 0.15)
				)
			)
		)
		(property "Datasheet" "https://industrial.panasonic.com/cdbs/www-data/pdf/RDA0000/AOA0000C301.pdf"
			(at 0 0 0)
			(layer "F.Fab")
			(hide yes)
			(effects
				(font
					(size 1.27 1.27)
					(thickness 0.15)
				)
			)
		)
		(property "Author" "Antmicro"
			(at 0 0 0)
			(layer "F.Fab")
			(hide yes)
			(effects
				(font
					(size 1 1)
					(thickness 0.15)
				)
			)
		)
		(property "Current" "1A"
			(at 0 0 0)
			(layer "F.Fab")
			(hide yes)
			(effects
				(font
					(size 1 1)
					(thickness 0.15)
				)
			)
		)
		(property "License" "Apache-2.0"
			(at 0 0 0)
			(layer "F.Fab")
			(hide yes)
			(effects
				(font
					(size 1 1)
					(thickness 0.15)
				)
			)
		)
		(property "MPN" "ERJ2GE0R00X"
			(at 0 0 0)
			(layer "F.Fab")
			(hide yes)
			(effects
				(font
					(size 1 1)
					(thickness 0.15)
				)
			)
		)
		(property "Manufacturer" "Panasonic"
			(at 0 0 0)
			(layer "F.Fab")
			(hide yes)
			(effects
				(font
					(size 1 1)
					(thickness 0.15)
				)
			)
		)
		(property "Tolerance" ""
			(at 0 0 0)
			(layer "F.Fab")
			(hide yes)
			(effects
				(font
					(size 1 1)
					(thickness 0.15)
				)
			)
		)
		(property "Val" "0R"
			(at 0 0 0)
			(layer "F.Fab")
			(hide yes)
			(effects
				(font
					(size 1 1)
					(thickness 0.15)
				)
			)
		)
		(sheetname "USB3")
		(sheetfile "usb3.kicad_sch")
		(attr smd)
		(fp_rect
			(start -0.925 -0.47)
			(end 0.925 0.47)
			(stroke
				(width 0.05)
				(type default)
			)
			(fill none)
			(layer "F.CrtYd")
		)
		(fp_rect
			(start -0.5 -0.25)
			(end 0.5 0.25)
			(stroke
				(width 0.15)
				(type solid)
			)
			(fill none)
			(layer "F.Fab")
		)
		(fp_text user "License: Apache-2.0"
			(at -0.95 5.169 0)
			(layer "F.Fab")
			(hide yes)
			(effects
				(font
					(size 0.7 0.7)
					(thickness 0.15)
				)
				(justify left bottom)
			)
		)
		(fp_text user "${REFERENCE}"
			(at -0.95 3.168 0)
			(layer "F.Fab")
			(hide yes)
			(effects
				(font
					(size 0.7 0.7)
					(thickness 0.15)
				)
				(justify left bottom)
			)
		)
		(fp_text user "Author: Antmicro"
			(at -0.95 4.169 0)
			(layer "F.Fab")
			(hide yes)
			(effects
				(font
					(size 0.7 0.7)
					(thickness 0.15)
				)
				(justify left bottom)
			)
		)
		(pad "1" smd roundrect
			(at -0.48 0)
			(size 0.59 0.64)
			(layers "F.Cu" "F.Paste" "F.Mask")
			(roundrect_rratio 0.25)
			(net 165 "USBSS2_RX_P")
			(pintype "passive")
		)
		(pad "2" smd roundrect
			(at 0.48 0)
			(size 0.59 0.64)
			(layers "F.Cu" "F.Paste" "F.Mask")
			(roundrect_rratio 0.25)
			(net 609 "/USB3/USBSS1_C_RX_N")
			(pintype "passive")
		)
	)
	(footprint "antmicro-footprints:C_0402_1005Metric"
		(layer "F.Cu")
		(at 148 112.79)
		(descr "Capacitor SMD 0402")
		(tags "capacitor SMD 0402")
		(property "Reference" "C114"
			(at -1.21 5.51 0)
			(layer "F.SilkS")
			(effects
				(font
					(size 0.7 0.7)
					(thickness 0.15)
				)
				(justify left bottom)
			)
		)
		(property "Value" "C_1u_0402"
			(at 0 1.4 0)
			(layer "F.Fab")
			(effects
				(font
					(size 0.7 0.7)
					(thickness 0.15)
				)
				(justify left bottom)
			)
		)
		(property "Footprint" "antmicro-footprints:C_0402_1005Metric"
			(at 0 0 0)
			(layer "F.Fab")
			(hide yes)
			(effects
				(font
					(size 1.27 1.27)
					(thickness 0.15)
				)
			)
		)
		(property "Datasheet" "https://product.tdk.com/en/search/capacitor/ceramic/mlcc/info?part_no=C1005X6S1A105K050BC"
			(at 0 0 0)
			(layer "F.Fab")
			(hide yes)
			(effects
				(font
					(size 1.27 1.27)
					(thickness 0.15)
				)
			)
		)
		(property "Author" "Antmicro"
			(at 0 0 0)
			(layer "F.Fab")
			(hide yes)
			(effects
				(font
					(size 1 1)
					(thickness 0.15)
				)
			)
		)
		(property "Dielectric" ""
			(at 0 0 0)
			(layer "F.Fab")
			(hide yes)
			(effects
				(font
					(size 1 1)
					(thickness 0.15)
				)
			)
		)
		(property "License" "Apache-2.0"
			(at 0 0 0)
			(layer "F.Fab")
			(hide yes)
			(effects
				(font
					(size 1 1)
					(thickness 0.15)
				)
			)
		)
		(property "MPN" "C1005X6S1A105K050BC"
			(at 0 0 0)
			(layer "F.Fab")
			(hide yes)
			(effects
				(font
					(size 1 1)
					(thickness 0.15)
				)
			)
		)
		(property "Manufacturer" "TDK"
			(at 0 0 0)
			(layer "F.Fab")
			(hide yes)
			(effects
				(font
					(size 1 1)
					(thickness 0.15)
				)
			)
		)
		(property "Val" "1u"
			(at 0 0 0)
			(layer "F.Fab")
			(hide yes)
			(effects
				(font
					(size 1 1)
					(thickness 0.15)
				)
			)
		)
		(property "Voltage" ""
			(at 0 0 0)
			(layer "F.Fab")
			(hide yes)
			(effects
				(font
					(size 1 1)
					(thickness 0.15)
				)
			)
		)
		(sheetname "Peripherals")
		(sheetfile "peripherals.kicad_sch")
		(attr smd)
		(fp_rect
			(start -0.925 -0.47)
			(end 0.925 0.47)
			(stroke
				(width 0.05)
				(type default)
			)
			(fill none)
			(layer "F.CrtYd")
		)
		(fp_line
			(start -0.494 -0.25)
			(end 0.504 -0.25)
			(stroke
				(width 0.15)
				(type solid)
			)
			(layer "F.Fab")
		)
		(fp_line
			(start -0.494 0.248)
			(end -0.494 -0.25)
			(stroke
				(width 0.15)
				(type solid)
			)
			(layer "F.Fab")
		)
		(fp_line
			(start 0.504 -0.25)
			(end 0.504 0.248)
			(stroke
				(width 0.15)
				(type solid)
			)
			(layer "F.Fab")
		)
		(fp_line
			(start 0.504 0.248)
			(end -0.494 0.248)
			(stroke
				(width 0.15)
				(type solid)
			)
			(layer "F.Fab")
		)
		(fp_text user "Author: Antmicro"
			(at -0.932 4.17 0)
			(layer "F.Fab")
			(hide yes)
			(effects
				(font
					(size 0.7 0.7)
					(thickness 0.15)
				)
				(justify left bottom)
			)
		)
		(fp_text user "${REFERENCE}"
			(at -0.932 3.168 0)
			(layer "F.Fab")
			(hide yes)
			(effects
				(font
					(size 0.7 0.7)
					(thickness 0.15)
				)
				(justify left bottom)
			)
		)
		(fp_text user "License: Apache-2.0"
			(at -0.932 5.17 0)
			(layer "F.Fab")
			(hide yes)
			(effects
				(font
					(size 0.7 0.7)
					(thickness 0.15)
				)
				(justify left bottom)
			)
		)
		(pad "1" smd roundrect
			(at -0.48 0)
			(size 0.59 0.64)
			(layers "F.Cu" "F.Paste" "F.Mask")
			(roundrect_rratio 0.25)
			(net 484 "/Peripherals/3V3_STDB_CONN")
			(pintype "passive")
		)
		(pad "2" smd roundrect
			(at 0.48 0)
			(size 0.59 0.64)
			(layers "F.Cu" "F.Paste" "F.Mask")
			(roundrect_rratio 0.25)
			(net 1 "GND")
			(pintype "passive")
		)
	)
	(footprint "antmicro-footprints:R_0402_1005Metric"
		(layer "F.Cu")
		(at 127.9 107.9 -90)
		(descr "Resistor SMD 0402")
		(tags "resistor SMD 0402")
		(property "Reference" "R186"
			(at 3.85 -0.37 -90)
			(layer "F.SilkS")
			(effects
				(font
					(size 0.7 0.7)
					(thickness 0.15)
				)
				(justify left bottom)
			)
		)
		(property "Value" "R_200R_0402"
			(at 0 1.4 -90)
			(layer "F.Fab")
			(effects
				(font
					(size 0.7 0.7)
					(thickness 0.15)
				)
				(justify left bottom)
			)
		)
		(property "Footprint" "antmicro-footprints:R_0402_1005Metric"
			(at 0 0 -90)
			(layer "F.Fab")
			(hide yes)
			(effects
				(font
					(size 1.27 1.27)
					(thickness 0.15)
				)
			)
		)
		(property "Datasheet" "https://www.bourns.com/docs/product-datasheets/cr.pdf"
			(at 0 0 -90)
			(layer "F.Fab")
			(hide yes)
			(effects
				(font
					(size 1.27 1.27)
					(thickness 0.15)
				)
			)
		)
		(property "Author" "Antmicro"
			(at 20 235.8 0)
			(layer "F.Fab")
			(hide yes)
			(effects
				(font
					(size 1 1)
					(thickness 0.15)
				)
			)
		)
		(property "License" "Apache-2.0"
			(at 20 235.8 0)
			(layer "F.Fab")
			(hide yes)
			(effects
				(font
					(size 1 1)
					(thickness 0.15)
				)
			)
		)
		(property "MPN" "CR0402-FX-2000GLF"
			(at 20 235.8 0)
			(layer "F.Fab")
			(hide yes)
			(effects
				(font
					(size 1 1)
					(thickness 0.15)
				)
			)
		)
		(property "Manufacturer" "Bourns"
			(at 20 235.8 0)
			(layer "F.Fab")
			(hide yes)
			(effects
				(font
					(size 1 1)
					(thickness 0.15)
				)
			)
		)
		(property "Tolerance" "1%"
			(at 20 235.8 0)
			(layer "F.Fab")
			(hide yes)
			(effects
				(font
					(size 1 1)
					(thickness 0.15)
				)
			)
		)
		(property "Val" "200R"
			(at 20 235.8 0)
			(layer "F.Fab")
			(hide yes)
			(effects
				(font
					(size 1 1)
					(thickness 0.15)
				)
			)
		)
		(sheetname "M.2")
		(sheetfile "m-2.kicad_sch")
		(attr smd)
		(fp_rect
			(start -0.925 -0.47)
			(end 0.925 0.47)
			(stroke
				(width 0.05)
				(type default)
			)
			(fill none)
			(layer "F.CrtYd")
		)
		(fp_rect
			(start -0.5 -0.25)
			(end 0.5 0.25)
			(stroke
				(width 0.15)
				(type solid)
			)
			(fill none)
			(layer "F.Fab")
		)
		(fp_text user "Author: Antmicro"
			(at -0.95 4.169 -90)
			(layer "F.Fab")
			(hide yes)
			(effects
				(font
					(size 0.7 0.7)
					(thickness 0.15)
				)
				(justify left bottom)
			)
		)
		(fp_text user "License: Apache-2.0"
			(at -0.95 5.169 -90)
			(layer "F.Fab")
			(hide yes)
			(effects
				(font
					(size 0.7 0.7)
					(thickness 0.15)
				)
				(justify left bottom)
			)
		)
		(fp_text user "${REFERENCE}"
			(at -0.95 3.168 -90)
			(layer "F.Fab")
			(hide yes)
			(effects
				(font
					(size 0.7 0.7)
					(thickness 0.15)
				)
				(justify left bottom)
			)
		)
		(pad "1" smd roundrect
			(at -0.48 0 270)
			(size 0.59 0.64)
			(layers "F.Cu" "F.Paste" "F.Mask")
			(roundrect_rratio 0.25)
			(net 184 "Net-(D51-A)")
			(pintype "passive")
		)
		(pad "2" smd roundrect
			(at 0.48 0 270)
			(size 0.59 0.64)
			(layers "F.Cu" "F.Paste" "F.Mask")
			(roundrect_rratio 0.25)
			(net 87 "+3V3")
			(pintype "passive")
		)
	)
)
